# S9S_MB_2U (Grand Teton) — schematic netlist excerpt (pin names and nets, part order shuffled) for the footprints in the layout excerpt that follows; sources: Cadence DE-HDL packaged netlist, KiCad conversion of 03242023_DA0F0TMBIJ0_F0T_Motherboard_J_brd_V01_OCP.brd

R5234  Q_RES  0 5% CHIP  pkg 0402LF  page 152 : A = USB2_HUB_BUF_SWB_R_DP ; B = USB2_HUB_BUF_SWB_DP
R3166  Q_RES  4.7K 1% EMPTY  pkg 0402LF  page 159 : A = P3V3_OCP_V3_2 ; B = OCP_V3_2_ID1

(kicad_pcb
	(version 20260206)
	(generator "pcbnew")
	(generator_version "10.0")
	(general
		(thickness 1.6)
		(legacy_teardrops no)
	)
	(paper "A4")
	(title_block
		(title "03242023_DA0F0TMBIJ0_F0T_Motherboard_J_brd_V01_OCP.brd")
		(comment 1 "Grand Teton / footprints 4956-4957 of 6105")
	)
	(layers
		(0 "F.Cu" signal "TOP")
		(4 "In1.Cu" signal "GND")
		(6 "In2.Cu" signal "IN1")
		(8 "In3.Cu" signal "GND1")
		(10 "In4.Cu" signal "IN2")
		(12 "In5.Cu" signal "GND2")
		(14 "In6.Cu" signal "IN3")
		(16 "In7.Cu" signal "GND3")
		(18 "In8.Cu" signal "VCC")
		(20 "In9.Cu" signal "VCC1")
		(22 "In10.Cu" signal "GND4")
		(24 "In11.Cu" signal "IN4")
		(26 "In12.Cu" signal "GND5")
		(28 "In13.Cu" signal "IN5")
		(30 "In14.Cu" signal "GND6")
		(32 "In15.Cu" signal "IN6")
		(34 "In16.Cu" signal "GND7")
		(2 "B.Cu" signal "BOTTOM")
		(9 "F.Adhes" user "F.Adhesive")
		(11 "B.Adhes" user "B.Adhesive")
		(13 "F.Paste" user "Package Geometry/Pastemask Top")
		(15 "B.Paste" user "Package Geometry/Pastemask Bottom")
		(5 "F.SilkS" user "Ref Des/Silkscreen Top")
		(7 "B.SilkS" user "Ref Des/Silkscreen Bottom")
		(1 "F.Mask" user "Board Geometry/Soldermask Top")
		(3 "B.Mask" user "Board Geometry/Soldermask Bottom")
		(17 "Dwgs.User" user "User.Drawings")
		(19 "Cmts.User" user "User.Comments")
		(21 "Eco1.User" user "User.Eco1")
		(23 "Eco2.User" user "User.Eco2")
		(25 "Edge.Cuts" user "Board Geometry/Outline")
		(27 "Margin" user)
		(31 "F.CrtYd" user "Package Geometry/Place Bound Top")
		(29 "B.CrtYd" user "Package Geometry/Place Bound Bottom")
		(35 "F.Fab" user "Ref Des/Assembly Top")
		(33 "B.Fab" user "Ref Des/Assembly Bottom")
	)
	(footprint ""
		(layer "B.Cu")
		(at 75.06208 -4.251198 -90)
		(property "Reference" "R3166"
			(at 0 0 90)
			(layer "B.SilkS")
			(hide yes)
			(effects
				(font
					(size 1.27 1.27)
				)
				(justify mirror)
			)
		)
		(property "Value" ""
			(at 0 0 90)
			(layer "B.Fab")
			(effects
				(font
					(size 1.27 1.27)
				)
				(justify mirror)
			)
		)
		(duplicate_pad_numbers_are_jumpers no)
		(fp_line
			(start -0.7874 0.4064)
			(end 0.7874 0.4064)
			(stroke
				(width 0.1524)
				(type default)
			)
			(layer "B.SilkS")
		)
		(fp_line
			(start 0.7874 0.4064)
			(end 0.7874 -0.4064)
			(stroke
				(width 0.1524)
				(type default)
			)
			(layer "B.SilkS")
		)
		(fp_line
			(start -0.7874 -0.4064)
			(end -0.7874 0.4064)
			(stroke
				(width 0.1524)
				(type default)
			)
			(layer "B.SilkS")
		)
		(fp_line
			(start 0.7874 -0.4064)
			(end -0.7874 -0.4064)
			(stroke
				(width 0.1524)
				(type default)
			)
			(layer "B.SilkS")
		)
		(fp_line
			(start -0.67945 0.3048)
			(end -0.120396 0.3048)
			(stroke
				(width 0.1)
				(type default)
			)
			(layer "B.Fab")
		)
		(fp_line
			(start -0.120396 0.3048)
			(end -0.120396 0.2794)
			(stroke
				(width 0.1)
				(type default)
			)
			(layer "B.Fab")
		)
		(fp_line
			(start 0.12065 0.3048)
			(end 0.67945 0.3048)
			(stroke
				(width 0.1)
				(type default)
			)
			(layer "B.Fab")
		)
		(fp_line
			(start 0.67945 0.3048)
			(end 0.67945 -0.305054)
			(stroke
				(width 0.1)
				(type default)
			)
			(layer "B.Fab")
		)
		(fp_line
			(start -0.120396 0.2794)
			(end 0.12065 0.2794)
			(stroke
				(width 0.1)
				(type default)
			)
			(layer "B.Fab")
		)
		(fp_line
			(start 0.12065 0.2794)
			(end 0.12065 0.3048)
			(stroke
				(width 0.1)
				(type default)
			)
			(layer "B.Fab")
		)
		(fp_line
			(start -0.12065 -0.2794)
			(end -0.12065 -0.3048)
			(stroke
				(width 0.1)
				(type default)
			)
			(layer "B.Fab")
		)
		(fp_line
			(start 0.12065 -0.2794)
			(end -0.12065 -0.2794)
			(stroke
				(width 0.1)
				(type default)
			)
			(layer "B.Fab")
		)
		(fp_line
			(start -0.67945 -0.3048)
			(end -0.67945 0.3048)
			(stroke
				(width 0.1)
				(type default)
			)
			(layer "B.Fab")
		)
		(fp_line
			(start -0.12065 -0.3048)
			(end -0.67945 -0.3048)
			(stroke
				(width 0.1)
				(type default)
			)
			(layer "B.Fab")
		)
		(fp_line
			(start 0.12065 -0.305054)
			(end 0.12065 -0.2794)
			(stroke
				(width 0.1)
				(type default)
			)
			(layer "B.Fab")
		)
		(fp_line
			(start 0.67945 -0.305054)
			(end 0.12065 -0.305054)
			(stroke
				(width 0.1)
				(type default)
			)
			(layer "B.Fab")
		)
		(pad "1" smd circle
			(at 0.40005 0 90)
			(size 0 0)
			(layers "B.Cu" "B.Mask" "B.Paste")
			(net "P3V3_OCP_V3_2")
		)
		(pad "2" smd circle
			(at -0.40005 0 90)
			(size 0 0)
			(layers "B.Cu" "B.Mask" "B.Paste")
			(net "OCP_V3_2_ID1")
		)
	)
	(footprint ""
		(layer "B.Cu")
		(at 36.488624 -405.93137 180)
		(property "Reference" "R5234"
			(at 0 0 0)
			(layer "B.SilkS")
			(hide yes)
			(effects
				(font
					(size 1.27 1.27)
				)
				(justify mirror)
			)
		)
		(property "Value" ""
			(at 0 0 0)
			(layer "B.Fab")
			(effects
				(font
					(size 1.27 1.27)
				)
				(justify mirror)
			)
		)
		(duplicate_pad_numbers_are_jumpers no)
		(fp_line
			(start 0.7874 -0.076962)
			(end 0.7874 -0.4064)
			(stroke
				(width 0.1524)
				(type default)
			)
			(layer "B.SilkS")
		)
		(fp_line
			(start 0.7874 -0.4064)
			(end -0.7874 -0.4064)
			(stroke
				(width 0.1524)
				(type default)
			)
			(layer "B.SilkS")
		)
		(fp_line
			(start -0.407416 0.4064)
			(end 0.529844 0.4064)
			(stroke
				(width 0.1524)
				(type default)
			)
			(layer "B.SilkS")
		)
		(fp_line
			(start -0.7874 -0.4064)
			(end -0.7874 0.027178)
			(stroke
				(width 0.1524)
				(type default)
			)
			(layer "B.SilkS")
		)
		(fp_line
			(start 0.67945 0.3048)
			(end 0.67945 -0.305054)
			(stroke
				(width 0.1)
				(type default)
			)
			(layer "B.Fab")
		)
		(fp_line
			(start 0.67945 -0.305054)
			(end 0.12065 -0.305054)
			(stroke
				(width 0.1)
				(type default)
			)
			(layer "B.Fab")
		)
		(fp_line
			(start 0.12065 0.3048)
			(end 0.67945 0.3048)
			(stroke
				(width 0.1)
				(type default)
			)
			(layer "B.Fab")
		)
		(fp_line
			(start 0.12065 0.2794)
			(end 0.12065 0.3048)
			(stroke
				(width 0.1)
				(type default)
			)
			(layer "B.Fab")
		)
		(fp_line
			(start 0.12065 -0.2794)
			(end -0.12065 -0.2794)
			(stroke
				(width 0.1)
				(type default)
			)
			(layer "B.Fab")
		)
		(fp_line
			(start 0.12065 -0.305054)
			(end 0.12065 -0.2794)
			(stroke
				(width 0.1)
				(type default)
			)
			(layer "B.Fab")
		)
		(fp_line
			(start -0.120396 0.3048)
			(end -0.120396 0.2794)
			(stroke
				(width 0.1)
				(type default)
			)
			(layer "B.Fab")
		)
		(fp_line
			(start -0.120396 0.2794)
			(end 0.12065 0.2794)
			(stroke
				(width 0.1)
				(type default)
			)
			(layer "B.Fab")
		)
		(fp_line
			(start -0.12065 -0.2794)
			(end -0.12065 -0.3048)
			(stroke
				(width 0.1)
				(type default)
			)
			(layer "B.Fab")
		)
		(fp_line
			(start -0.12065 -0.3048)
			(end -0.67945 -0.3048)
			(stroke
				(width 0.1)
				(type default)
			)
			(layer "B.Fab")
		)
		(fp_line
			(start -0.67945 0.3048)
			(end -0.120396 0.3048)
			(stroke
				(width 0.1)
				(type default)
			)
			(layer "B.Fab")
		)
		(fp_line
			(start -0.67945 -0.3048)
			(end -0.67945 0.3048)
			(stroke
				(width 0.1)
				(type default)
			)
			(layer "B.Fab")
		)
		(pad "1" smd circle
			(at 0.40005 0)
			(size 0 0)
			(layers "B.Cu" "B.Mask" "B.Paste")
			(net "USB2_HUB_BUF_SWB_R_DP")
		)
		(pad "2" smd circle
			(at -0.40005 0)
			(size 0 0)
			(layers "B.Cu" "B.Mask" "B.Paste")
			(net "USB2_HUB_BUF_SWB_DP")
		)
	)
)
